# T6G (Grand Teton) — schematic netlist excerpt (pin names and nets, part order shuffled) for the footprints in the layout excerpt that follows; sources: Cadence DE-HDL packaged netlist, KiCad conversion of 04192023_DAF0TMB3IC0_F0TG_MB_C_brd_V02_OCP.brd

R6235  Q_RES  10K 1% EMPTY  pkg 0402LF  page 267 : A = A_HSC_HIGH ; B = GND
C442  Q_CAP  1UF 4V 20% X6S  pkg 0201  page 356 : A = P1V8_CPU1_RT3_1A ; B = GND
C549  Q_CAP  10UF 25V 10% X6S  pkg C0805  page 109 : A = P12V_MEM_CPU1 ; B = GND
R1462  Q_RES  1K 1% CHIP  pkg 0201LF  page 185 : A = P1V8_CPU1_RT_1D ; B = SMB_RT_CPU1_P3_ROM_MUX_1D_SDA

(kicad_pcb
	(version 20260206)
	(generator "pcbnew")
	(generator_version "10.0")
	(general
		(thickness 1.6)
		(legacy_teardrops no)
	)
	(paper "A4")
	(title_block
		(title "04192023_DAF0TMB3IC0_F0TG_MB_C_brd_V02_OCP.brd")
		(comment 1 "Grand Teton / footprints 5144-5147 of 8354")
	)
	(layers
		(0 "F.Cu" signal "TOP")
		(4 "In1.Cu" signal "GND")
		(6 "In2.Cu" signal "IN1")
		(8 "In3.Cu" signal "GND1")
		(10 "In4.Cu" signal "IN2")
		(12 "In5.Cu" signal "GND2")
		(14 "In6.Cu" signal "IN3")
		(16 "In7.Cu" signal "GND3")
		(18 "In8.Cu" signal "VCC")
		(20 "In9.Cu" signal "VCC1")
		(22 "In10.Cu" signal "GND4")
		(24 "In11.Cu" signal "IN4")
		(26 "In12.Cu" signal "GND5")
		(28 "In13.Cu" signal "IN5")
		(30 "In14.Cu" signal "GND6")
		(32 "In15.Cu" signal "IN6")
		(34 "In16.Cu" signal "GND7")
		(2 "B.Cu" signal "BOTTOM")
		(9 "F.Adhes" user "F.Adhesive")
		(11 "B.Adhes" user "B.Adhesive")
		(13 "F.Paste" user "Package Geometry/Pastemask Top")
		(15 "B.Paste" user "Package Geometry/Pastemask Bottom")
		(5 "F.SilkS" user "Ref Des/Silkscreen Top")
		(7 "B.SilkS" user "Ref Des/Silkscreen Bottom")
		(1 "F.Mask" user "Board Geometry/Soldermask Top")
		(3 "B.Mask" user "Board Geometry/Soldermask Bottom")
		(17 "Dwgs.User" user "User.Drawings")
		(19 "Cmts.User" user "User.Comments")
		(21 "Eco1.User" user "User.Eco1")
		(23 "Eco2.User" user "User.Eco2")
		(25 "Edge.Cuts" user "Board Geometry/Outline")
		(27 "Margin" user)
		(31 "F.CrtYd" user "Package Geometry/Place Bound Top")
		(29 "B.CrtYd" user "Package Geometry/Place Bound Bottom")
		(35 "F.Fab" user "Ref Des/Assembly Top")
		(33 "B.Fab" user "Ref Des/Assembly Bottom")
	)
	(footprint ""
		(layer "B.Cu")
		(at 182.308246 -421.375586 90)
		(property "Reference" "R6235"
			(at 0 0 90)
			(layer "B.SilkS")
			(hide yes)
			(effects
				(font
					(size 1.27 1.27)
				)
				(justify mirror)
			)
		)
		(property "Value" ""
			(at 0 0 90)
			(layer "B.Fab")
			(effects
				(font
					(size 1.27 1.27)
				)
				(justify mirror)
			)
		)
		(duplicate_pad_numbers_are_jumpers no)
		(fp_line
			(start 0.7874 -0.4064)
			(end -0.7874 -0.4064)
			(stroke
				(width 0.1524)
				(type default)
			)
			(layer "B.SilkS")
		)
		(fp_line
			(start -0.7874 -0.4064)
			(end -0.7874 0.4064)
			(stroke
				(width 0.1524)
				(type default)
			)
			(layer "B.SilkS")
		)
		(fp_line
			(start 0.7874 0.4064)
			(end 0.7874 -0.4064)
			(stroke
				(width 0.1524)
				(type default)
			)
			(layer "B.SilkS")
		)
		(fp_line
			(start -0.7874 0.4064)
			(end 0.7874 0.4064)
			(stroke
				(width 0.1524)
				(type default)
			)
			(layer "B.SilkS")
		)
		(fp_line
			(start 0.67945 -0.305054)
			(end 0.12065 -0.305054)
			(stroke
				(width 0.1)
				(type default)
			)
			(layer "B.Fab")
		)
		(fp_line
			(start 0.12065 -0.305054)
			(end 0.12065 -0.2794)
			(stroke
				(width 0.1)
				(type default)
			)
			(layer "B.Fab")
		)
		(fp_line
			(start -0.12065 -0.3048)
			(end -0.67945 -0.3048)
			(stroke
				(width 0.1)
				(type default)
			)
			(layer "B.Fab")
		)
		(fp_line
			(start -0.67945 -0.3048)
			(end -0.67945 0.3048)
			(stroke
				(width 0.1)
				(type default)
			)
			(layer "B.Fab")
		)
		(fp_line
			(start 0.12065 -0.2794)
			(end -0.12065 -0.2794)
			(stroke
				(width 0.1)
				(type default)
			)
			(layer "B.Fab")
		)
		(fp_line
			(start -0.12065 -0.2794)
			(end -0.12065 -0.3048)
			(stroke
				(width 0.1)
				(type default)
			)
			(layer "B.Fab")
		)
		(fp_line
			(start 0.12065 0.2794)
			(end 0.12065 0.3048)
			(stroke
				(width 0.1)
				(type default)
			)
			(layer "B.Fab")
		)
		(fp_line
			(start -0.120396 0.2794)
			(end 0.12065 0.2794)
			(stroke
				(width 0.1)
				(type default)
			)
			(layer "B.Fab")
		)
		(fp_line
			(start 0.67945 0.3048)
			(end 0.67945 -0.305054)
			(stroke
				(width 0.1)
				(type default)
			)
			(layer "B.Fab")
		)
		(fp_line
			(start 0.12065 0.3048)
			(end 0.67945 0.3048)
			(stroke
				(width 0.1)
				(type default)
			)
			(layer "B.Fab")
		)
		(fp_line
			(start -0.120396 0.3048)
			(end -0.120396 0.2794)
			(stroke
				(width 0.1)
				(type default)
			)
			(layer "B.Fab")
		)
		(fp_line
			(start -0.67945 0.3048)
			(end -0.120396 0.3048)
			(stroke
				(width 0.1)
				(type default)
			)
			(layer "B.Fab")
		)
		(pad "1" smd circle
			(at 0.40005 0 270)
			(size 0 0)
			(layers "B.Cu" "B.Mask" "B.Paste")
			(net "A_HSC_HIGH")
		)
		(pad "2" smd circle
			(at -0.40005 0 270)
			(size 0 0)
			(layers "B.Cu" "B.Mask" "B.Paste")
			(net "GND")
		)
	)
	(footprint ""
		(layer "B.Cu")
		(at 123.01855 -388.011162 -90)
		(property "Reference" "C442"
			(at 0 0 90)
			(layer "B.SilkS")
			(hide yes)
			(effects
				(font
					(size 1.27 1.27)
				)
				(justify mirror)
			)
		)
		(property "Value" ""
			(at 0 0 90)
			(layer "B.Fab")
			(effects
				(font
					(size 1.27 1.27)
				)
				(justify mirror)
			)
		)
		(duplicate_pad_numbers_are_jumpers no)
		(fp_line
			(start -0.299974 0.150114)
			(end 0.299974 0.150114)
			(stroke
				(width 0.1)
				(type default)
			)
			(layer "B.Fab")
		)
		(fp_line
			(start 0.299974 0.150114)
			(end 0.299974 -0.150114)
			(stroke
				(width 0.1)
				(type default)
			)
			(layer "B.Fab")
		)
		(fp_line
			(start -0.299974 -0.150114)
			(end -0.299974 0.150114)
			(stroke
				(width 0.1)
				(type default)
			)
			(layer "B.Fab")
		)
		(fp_line
			(start 0.299974 -0.150114)
			(end -0.299974 -0.150114)
			(stroke
				(width 0.1)
				(type default)
			)
			(layer "B.Fab")
		)
		(pad "1" smd rect
			(at 0.2667 0 90)
			(size 0.3048 0.381)
			(layers "B.Cu" "B.Mask" "B.Paste")
			(net "P1V8_CPU1_RT3_1A")
		)
		(pad "2" smd rect
			(at -0.2667 0 90)
			(size 0.3048 0.381)
			(layers "B.Cu" "B.Mask" "B.Paste")
			(net "GND")
		)
	)
	(footprint ""
		(layer "B.Cu")
		(at 168.3004 -421.277796 -90)
		(property "Reference" "R1462"
			(at 0 0 90)
			(layer "B.SilkS")
			(hide yes)
			(effects
				(font
					(size 1.27 1.27)
				)
				(justify mirror)
			)
		)
		(property "Value" ""
			(at 0 0 90)
			(layer "B.Fab")
			(effects
				(font
					(size 1.27 1.27)
				)
				(justify mirror)
			)
		)
		(duplicate_pad_numbers_are_jumpers no)
		(fp_line
			(start -0.32512 0.175006)
			(end 0.32512 0.175006)
			(stroke
				(width 0.1)
				(type default)
			)
			(layer "B.Fab")
		)
		(fp_line
			(start 0.32512 0.175006)
			(end 0.32512 -0.175006)
			(stroke
				(width 0.1)
				(type default)
			)
			(layer "B.Fab")
		)
		(fp_line
			(start -0.32512 -0.175006)
			(end -0.32512 0.175006)
			(stroke
				(width 0.1)
				(type default)
			)
			(layer "B.Fab")
		)
		(fp_line
			(start 0.32512 -0.175006)
			(end -0.32512 -0.175006)
			(stroke
				(width 0.1)
				(type default)
			)
			(layer "B.Fab")
		)
		(pad "1" smd rect
			(at 0.2667 0 90)
			(size 0.3048 0.381)
			(layers "B.Cu" "B.Mask" "B.Paste")
			(net "P1V8_CPU1_RT_1D")
		)
		(pad "2" smd rect
			(at -0.2667 0 270)
			(size 0.3048 0.381)
			(layers "B.Cu" "B.Mask" "B.Paste")
			(net "SMB_RT_CPU1_P3_ROM_MUX_1D_SDA")
		)
	)
	(footprint ""
		(layer "B.Cu")
		(at 202.148186 -192.660016 180)
		(property "Reference" "C549"
			(at 0 0 0)
			(layer "B.SilkS")
			(hide yes)
			(effects
				(font
					(size 1.27 1.27)
				)
				(justify mirror)
			)
		)
		(property "Value" ""
			(at 0 0 0)
			(layer "B.Fab")
			(effects
				(font
					(size 1.27 1.27)
				)
				(justify mirror)
			)
		)
		(duplicate_pad_numbers_are_jumpers no)
		(fp_line
			(start 1.524 0.762)
			(end 1.524 -0.762)
			(stroke
				(width 0.1524)
				(type default)
			)
			(layer "B.SilkS")
		)
		(fp_line
			(start 1.524 -0.762)
			(end -1.524 -0.762)
			(stroke
				(width 0.1524)
				(type default)
			)
			(layer "B.SilkS")
		)
		(fp_line
			(start -1.524 0.762)
			(end 1.524 0.762)
			(stroke
				(width 0.1524)
				(type default)
			)
			(layer "B.SilkS")
		)
		(fp_line
			(start -1.524 -0.762)
			(end -1.524 0.762)
			(stroke
				(width 0.1524)
				(type default)
			)
			(layer "B.SilkS")
		)
		(fp_line
			(start 1.1049 0.724916)
			(end -1.1049 0.724916)
			(stroke
				(width 0.1)
				(type default)
			)
			(layer "B.Fab")
		)
		(fp_line
			(start 1.1049 -0.724916)
			(end 1.1049 0.724916)
			(stroke
				(width 0.1)
				(type default)
			)
			(layer "B.Fab")
		)
		(fp_line
			(start -1.1049 0.724916)
			(end -1.1049 -0.724916)
			(stroke
				(width 0.1)
				(type default)
			)
			(layer "B.Fab")
		)
		(fp_line
			(start -1.1049 -0.724916)
			(end 1.1049 -0.724916)
			(stroke
				(width 0.1)
				(type default)
			)
			(layer "B.Fab")
		)
		(pad "1" smd rect
			(at 0.889 0 180)
			(size 1.016 1.27)
			(layers "B.Cu" "B.Mask" "B.Paste")
			(net "P12V_MEM_CPU1")
		)
		(pad "2" smd rect
			(at -0.889 0 180)
			(size 1.016 1.27)
			(layers "B.Cu" "B.Mask" "B.Paste")
			(net "GND")
		)
	)
)
